FILE_TYPE = MULTI_PHYS_TABLE;
PART '74CBTLV1G125'
{========================================================================================}
:PACK_TYPE|MATERIAL|PART_NUMBER= EnvComp |PART_NUMBER|JEDEC_TYPE|CLASS|DESCRIPTION|HEIGHT|COMPONENT_TYPE|LEAD_LENGTH| LPID   | SPEED_URL | Status |RPL| AML | Bus_Unit | Days ;
{========================================================================================}
'SMLF'    | 'IC'     | 'C88177-001'(!) = 'YES;YES;UNK;UNK;ok;VLD' | 'C88177-001' | 'SSOP5_53_65MA' | 'IC'  | 'FET BUS SW' | '0.043 IN' | 'SMALLSMT'     | '' | '' | 'http://speed.intel.com:8081/speed/module/pdm/item/pdm_item_detail_direct.asp?item_cde=C88177-001&item_rev=01&url_param=unused' | 'Conditional' | 'YES' | '1' | 'SMO_IC' | '28' 
'SMLF'    | 'EMPTY'  | 'C88177-001'(!) = 'YES;YES;UNK;UNK;ok;VLD' | 'C88177-001' | 'SSOP5_53_65MA' | 'IO'  | 'FET BUS SW' | '0.043 IN' | 'SMALLSMT'     | '' | '' | 'http://speed.intel.com:8081/speed/module/pdm/item/pdm_item_detail_direct.asp?item_cde=C88177-001&item_rev=01&url_param=unused' | 'Conditional' | 'YES' | '1' | 'SMO_IC' | '28' 
END_PART
END.
